# S9S_MB_2U (Grand Teton) — schematic netlist excerpt (pin names and nets, part order shuffled) for the footprints in the layout excerpt that follows; sources: Cadence DE-HDL packaged netlist, KiCad conversion of 03242023_DA0F0TMBIJ0_F0T_Motherboard_J_brd_V01_OCP.brd

R1205  Q_RES  33.2 1% CHIP  pkg 0402LF  page 223 : A = RST_PLTRST_N ; B = RST_PLTRST_PLD_N
C1405  Q_CAP  47UF 2.5V 20% X6S  pkg C0603  page 75 : A = PVNN_MAIN_CPU0 ; B = GND

(kicad_pcb
	(version 20260206)
	(generator "pcbnew")
	(generator_version "10.0")
	(general
		(thickness 1.6)
		(legacy_teardrops no)
	)
	(paper "A4")
	(title_block
		(title "03242023_DA0F0TMBIJ0_F0T_Motherboard_J_brd_V01_OCP.brd")
		(comment 1 "Grand Teton / footprints 4613-4614 of 6105")
	)
	(layers
		(0 "F.Cu" signal "TOP")
		(4 "In1.Cu" signal "GND")
		(6 "In2.Cu" signal "IN1")
		(8 "In3.Cu" signal "GND1")
		(10 "In4.Cu" signal "IN2")
		(12 "In5.Cu" signal "GND2")
		(14 "In6.Cu" signal "IN3")
		(16 "In7.Cu" signal "GND3")
		(18 "In8.Cu" signal "VCC")
		(20 "In9.Cu" signal "VCC1")
		(22 "In10.Cu" signal "GND4")
		(24 "In11.Cu" signal "IN4")
		(26 "In12.Cu" signal "GND5")
		(28 "In13.Cu" signal "IN5")
		(30 "In14.Cu" signal "GND6")
		(32 "In15.Cu" signal "IN6")
		(34 "In16.Cu" signal "GND7")
		(2 "B.Cu" signal "BOTTOM")
		(9 "F.Adhes" user "F.Adhesive")
		(11 "B.Adhes" user "B.Adhesive")
		(13 "F.Paste" user "Package Geometry/Pastemask Top")
		(15 "B.Paste" user "Package Geometry/Pastemask Bottom")
		(5 "F.SilkS" user "Ref Des/Silkscreen Top")
		(7 "B.SilkS" user "Ref Des/Silkscreen Bottom")
		(1 "F.Mask" user "Board Geometry/Soldermask Top")
		(3 "B.Mask" user "Board Geometry/Soldermask Bottom")
		(17 "Dwgs.User" user "User.Drawings")
		(19 "Cmts.User" user "User.Comments")
		(21 "Eco1.User" user "User.Eco1")
		(23 "Eco2.User" user "User.Eco2")
		(25 "Edge.Cuts" user "Board Geometry/Outline")
		(27 "Margin" user)
		(31 "F.CrtYd" user "Package Geometry/Place Bound Top")
		(29 "B.CrtYd" user "Package Geometry/Place Bound Bottom")
		(35 "F.Fab" user "Ref Des/Assembly Top")
		(33 "B.Fab" user "Ref Des/Assembly Bottom")
	)
	(footprint ""
		(layer "B.Cu")
		(at 193.38036 -120.614948)
		(property "Reference" "R1205"
			(at 0 0 0)
			(layer "B.SilkS")
			(hide yes)
			(effects
				(font
					(size 1.27 1.27)
				)
				(justify mirror)
			)
		)
		(property "Value" ""
			(at 0 0 0)
			(layer "B.Fab")
			(effects
				(font
					(size 1.27 1.27)
				)
				(justify mirror)
			)
		)
		(duplicate_pad_numbers_are_jumpers no)
		(fp_line
			(start -0.7874 -0.4064)
			(end -0.7874 0.4064)
			(stroke
				(width 0.1524)
				(type default)
			)
			(layer "B.SilkS")
		)
		(fp_line
			(start -0.7874 0.4064)
			(end 0.7874 0.4064)
			(stroke
				(width 0.1524)
				(type default)
			)
			(layer "B.SilkS")
		)
		(fp_line
			(start 0.7874 -0.4064)
			(end -0.7874 -0.4064)
			(stroke
				(width 0.1524)
				(type default)
			)
			(layer "B.SilkS")
		)
		(fp_line
			(start 0.7874 0.4064)
			(end 0.7874 -0.4064)
			(stroke
				(width 0.1524)
				(type default)
			)
			(layer "B.SilkS")
		)
		(fp_line
			(start -0.67945 -0.3048)
			(end -0.67945 0.3048)
			(stroke
				(width 0.1)
				(type default)
			)
			(layer "B.Fab")
		)
		(fp_line
			(start -0.67945 0.3048)
			(end -0.120396 0.3048)
			(stroke
				(width 0.1)
				(type default)
			)
			(layer "B.Fab")
		)
		(fp_line
			(start -0.12065 -0.3048)
			(end -0.67945 -0.3048)
			(stroke
				(width 0.1)
				(type default)
			)
			(layer "B.Fab")
		)
		(fp_line
			(start -0.12065 -0.2794)
			(end -0.12065 -0.3048)
			(stroke
				(width 0.1)
				(type default)
			)
			(layer "B.Fab")
		)
		(fp_line
			(start -0.120396 0.2794)
			(end 0.12065 0.2794)
			(stroke
				(width 0.1)
				(type default)
			)
			(layer "B.Fab")
		)
		(fp_line
			(start -0.120396 0.3048)
			(end -0.120396 0.2794)
			(stroke
				(width 0.1)
				(type default)
			)
			(layer "B.Fab")
		)
		(fp_line
			(start 0.12065 -0.305054)
			(end 0.12065 -0.2794)
			(stroke
				(width 0.1)
				(type default)
			)
			(layer "B.Fab")
		)
		(fp_line
			(start 0.12065 -0.2794)
			(end -0.12065 -0.2794)
			(stroke
				(width 0.1)
				(type default)
			)
			(layer "B.Fab")
		)
		(fp_line
			(start 0.12065 0.2794)
			(end 0.12065 0.3048)
			(stroke
				(width 0.1)
				(type default)
			)
			(layer "B.Fab")
		)
		(fp_line
			(start 0.12065 0.3048)
			(end 0.67945 0.3048)
			(stroke
				(width 0.1)
				(type default)
			)
			(layer "B.Fab")
		)
		(fp_line
			(start 0.67945 -0.305054)
			(end 0.12065 -0.305054)
			(stroke
				(width 0.1)
				(type default)
			)
			(layer "B.Fab")
		)
		(fp_line
			(start 0.67945 0.3048)
			(end 0.67945 -0.305054)
			(stroke
				(width 0.1)
				(type default)
			)
			(layer "B.Fab")
		)
		(pad "1" smd circle
			(at 0.40005 0 180)
			(size 0 0)
			(layers "B.Cu" "B.Mask" "B.Paste")
			(net "RST_PLTRST_N")
		)
		(pad "2" smd circle
			(at -0.40005 0 180)
			(size 0 0)
			(layers "B.Cu" "B.Mask" "B.Paste")
			(net "RST_PLTRST_PLD_N")
		)
	)
	(footprint ""
		(layer "B.Cu")
		(at 353.924108 -237.709202 -90)
		(property "Reference" "C1405"
			(at 0 0 90)
			(layer "B.SilkS")
			(hide yes)
			(effects
				(font
					(size 1.27 1.27)
				)
				(justify mirror)
			)
		)
		(property "Value" ""
			(at 0 0 90)
			(layer "B.Fab")
			(effects
				(font
					(size 1.27 1.27)
				)
				(justify mirror)
			)
		)
		(duplicate_pad_numbers_are_jumpers no)
		(fp_line
			(start -1.2954 0.5842)
			(end 1.2954 0.5842)
			(stroke
				(width 0.1524)
				(type default)
			)
			(layer "B.SilkS")
		)
		(fp_line
			(start 1.2954 0.5842)
			(end 1.2954 -0.5842)
			(stroke
				(width 0.1524)
				(type default)
			)
			(layer "B.SilkS")
		)
		(fp_line
			(start -1.2954 -0.5842)
			(end -1.2954 0.5842)
			(stroke
				(width 0.1524)
				(type default)
			)
			(layer "B.SilkS")
		)
		(fp_line
			(start 0 -0.5842)
			(end 0 0.5842)
			(stroke
				(width 0.1524)
				(type default)
			)
			(layer "B.SilkS")
		)
		(fp_line
			(start 1.2954 -0.5842)
			(end -1.2954 -0.5842)
			(stroke
				(width 0.1524)
				(type default)
			)
			(layer "B.SilkS")
		)
		(fp_line
			(start -0.8636 0.4572)
			(end 0.8636 0.4572)
			(stroke
				(width 0.1)
				(type default)
			)
			(layer "B.Fab")
		)
		(fp_line
			(start 0.8636 0.4572)
			(end 0.8636 0.4064)
			(stroke
				(width 0.1)
				(type default)
			)
			(layer "B.Fab")
		)
		(fp_line
			(start -1.1938 0.4064)
			(end -0.8636 0.4064)
			(stroke
				(width 0.1)
				(type default)
			)
			(layer "B.Fab")
		)
		(fp_line
			(start -0.8636 0.4064)
			(end -0.8636 0.4572)
			(stroke
				(width 0.1)
				(type default)
			)
			(layer "B.Fab")
		)
		(fp_line
			(start 0.8636 0.4064)
			(end 1.1938 0.4064)
			(stroke
				(width 0.1)
				(type default)
			)
			(layer "B.Fab")
		)
		(fp_line
			(start 1.1938 0.4064)
			(end 1.1938 -0.4064)
			(stroke
				(width 0.1)
				(type default)
			)
			(layer "B.Fab")
		)
		(fp_line
			(start -1.1938 -0.4064)
			(end -1.1938 0.4064)
			(stroke
				(width 0.1)
				(type default)
			)
			(layer "B.Fab")
		)
		(fp_line
			(start -0.8636 -0.4064)
			(end -1.1938 -0.4064)
			(stroke
				(width 0.1)
				(type default)
			)
			(layer "B.Fab")
		)
		(fp_line
			(start 0.8636 -0.4064)
			(end 0.8636 -0.4572)
			(stroke
				(width 0.1)
				(type default)
			)
			(layer "B.Fab")
		)
		(fp_line
			(start 1.1938 -0.4064)
			(end 0.8636 -0.4064)
			(stroke
				(width 0.1)
				(type default)
			)
			(layer "B.Fab")
		)
		(fp_line
			(start -0.8636 -0.4572)
			(end -0.8636 -0.4064)
			(stroke
				(width 0.1)
				(type default)
			)
			(layer "B.Fab")
		)
		(fp_line
			(start 0.8636 -0.4572)
			(end -0.8636 -0.4572)
			(stroke
				(width 0.1)
				(type default)
			)
			(layer "B.Fab")
		)
		(pad "1" smd rect
			(at 0.7366 0 180)
			(size 0.7112 0.8128)
			(layers "B.Cu" "B.Mask" "B.Paste")
			(net "PVNN_MAIN_CPU0")
		)
		(pad "2" smd rect
			(at -0.7366 0 180)
			(size 0.7112 0.8128)
			(layers "B.Cu" "B.Mask" "B.Paste")
			(net "GND")
		)
	)
)
